# SCM (Grand Teton) — schematic netlist excerpt (pin names and nets, part order shuffled) for the footprints in the layout excerpt that follows; sources: Cadence DE-HDL packaged netlist, KiCad conversion of 12092022_DA0F0TMDCD0_F0T_Management_Board_D_brd_V3_OCP.brd

R661  Q_RES  10K 1% EMPTY  pkg 0402LF  page 21 : A = P3V3_AUX ; B = EMMC_DT6_R
D7  Q_LED  IC  pkg SMLF  page 47 : A = LED_POSTCODE_7_R ; C = GND

(kicad_pcb
	(version 20260206)
	(generator "pcbnew")
	(generator_version "10.0")
	(general
		(thickness 1.6)
		(legacy_teardrops no)
	)
	(paper "A4")
	(title_block
		(title "12092022_DA0F0TMDCD0_F0T_Management_Board_D_brd_V3_OCP.brd")
		(comment 1 "Grand Teton / footprints 190-191 of 1440")
	)
	(layers
		(0 "F.Cu" signal "TOP")
		(4 "In1.Cu" signal "GND")
		(6 "In2.Cu" signal "IN1")
		(8 "In3.Cu" signal "GND1")
		(10 "In4.Cu" signal "IN2")
		(12 "In5.Cu" signal "VCC")
		(14 "In6.Cu" signal "VCC1")
		(16 "In7.Cu" signal "IN3")
		(18 "In8.Cu" signal "GND2")
		(20 "In9.Cu" signal "IN4")
		(22 "In10.Cu" signal "GND3")
		(2 "B.Cu" signal "BOTTOM")
		(9 "F.Adhes" user "F.Adhesive")
		(11 "B.Adhes" user "B.Adhesive")
		(13 "F.Paste" user "Package Geometry/Pastemask Top")
		(15 "B.Paste" user "Package Geometry/Pastemask Bottom")
		(5 "F.SilkS" user "Ref Des/Silkscreen Top")
		(7 "B.SilkS" user "Ref Des/Silkscreen Bottom")
		(1 "F.Mask" user "Board Geometry/Soldermask Top")
		(3 "B.Mask" user "Board Geometry/Soldermask Bottom")
		(17 "Dwgs.User" user "User.Drawings")
		(19 "Cmts.User" user "User.Comments")
		(21 "Eco1.User" user "User.Eco1")
		(23 "Eco2.User" user "User.Eco2")
		(25 "Edge.Cuts" user "Board Geometry/Outline")
		(27 "Margin" user)
		(31 "F.CrtYd" user "Package Geometry/Place Bound Top")
		(29 "B.CrtYd" user "Package Geometry/Place Bound Bottom")
		(35 "F.Fab" user "Ref Des/Assembly Top")
		(33 "B.Fab" user "Ref Des/Assembly Bottom")
	)
	(footprint ""
		(layer "F.Cu")
		(at 74.01052 -31.307786 90)
		(property "Reference" "D7"
			(at -3.672586 8.64235 90)
			(unlocked yes)
			(layer "F.SilkS")
			(effects
				(font
					(size 0.7874 0.5842)
					(thickness 0.1524)
				)
				(justify left)
			)
		)
		(property "Value" ""
			(at 0 0 90)
			(layer "F.Fab")
			(effects
				(font
					(size 1.27 1.27)
				)
			)
		)
		(duplicate_pad_numbers_are_jumpers no)
		(fp_line
			(start 1.778 -0.5588)
			(end 1.3208 -0.5588)
			(stroke
				(width 0.1524)
				(type default)
			)
			(layer "F.SilkS")
		)
		(fp_line
			(start 1.778 -0.5588)
			(end 1.778 0.5588)
			(stroke
				(width 0.1524)
				(type default)
			)
			(layer "F.SilkS")
		)
		(fp_line
			(start 1.4732 -0.5588)
			(end 1.4732 0.5588)
			(stroke
				(width 0.1524)
				(type default)
			)
			(layer "F.SilkS")
		)
		(fp_line
			(start 1.3208 -0.5588)
			(end 1.3208 0.5588)
			(stroke
				(width 0.1524)
				(type default)
			)
			(layer "F.SilkS")
		)
		(fp_line
			(start -1.3208 -0.5588)
			(end 1.3208 -0.5588)
			(stroke
				(width 0.1524)
				(type default)
			)
			(layer "F.SilkS")
		)
		(fp_line
			(start 1.778 0.5588)
			(end 1.3208 0.5588)
			(stroke
				(width 0.1524)
				(type default)
			)
			(layer "F.SilkS")
		)
		(fp_line
			(start 1.6256 0.5588)
			(end 1.6256 -0.5588)
			(stroke
				(width 0.1524)
				(type default)
			)
			(layer "F.SilkS")
		)
		(fp_line
			(start 1.3208 0.5588)
			(end -1.3208 0.5588)
			(stroke
				(width 0.1524)
				(type default)
			)
			(layer "F.SilkS")
		)
		(fp_line
			(start -1.3208 0.5588)
			(end -1.3208 -0.5588)
			(stroke
				(width 0.1524)
				(type default)
			)
			(layer "F.SilkS")
		)
		(fp_line
			(start 0.8001 -0.40005)
			(end 0.8001 0.40005)
			(stroke
				(width 0.1)
				(type default)
			)
			(layer "F.Fab")
		)
		(fp_line
			(start -0.8001 -0.40005)
			(end 0.8001 -0.40005)
			(stroke
				(width 0.1)
				(type default)
			)
			(layer "F.Fab")
		)
		(fp_line
			(start 0.8001 0.40005)
			(end -0.8001 0.40005)
			(stroke
				(width 0.1)
				(type default)
			)
			(layer "F.Fab")
		)
		(fp_line
			(start -0.8001 0.40005)
			(end -0.8001 -0.40005)
			(stroke
				(width 0.1)
				(type default)
			)
			(layer "F.Fab")
		)
		(fp_text user "+"
			(at -0.811276 -0.6985 270)
			(unlocked yes)
			(layer "F.SilkS")
			(effects
				(font
					(size 1.905 1.4224)
					(thickness 0.1524)
				)
				(justify left)
			)
		)
		(fp_text user "-"
			(at 1.6256 -0.22225 90)
			(unlocked yes)
			(layer "F.SilkS")
			(effects
				(font
					(size 1.905 1.4224)
					(thickness 0.1524)
				)
				(justify left)
			)
		)
		(fp_text user "-"
			(at 1.6256 -0.22225 90)
			(unlocked yes)
			(layer "F.Fab")
			(effects
				(font
					(size 1.905 1.4224)
					(thickness 0.1524)
				)
				(justify left)
			)
		)
		(fp_text user "+"
			(at -2.5654 -0.22225 90)
			(unlocked yes)
			(layer "F.Fab")
			(effects
				(font
					(size 1.905 1.4224)
					(thickness 0.1524)
				)
				(justify left)
			)
		)
		(pad "A" smd rect
			(at -0.750062 0 90)
			(size 0.8128 0.8128)
			(layers "F.Cu" "F.Mask" "F.Paste")
			(net "LED_POSTCODE_7_R")
		)
		(pad "C" smd rect
			(at 0.750062 0 90)
			(size 0.8128 0.8128)
			(layers "F.Cu" "F.Mask" "F.Paste")
			(net "GND")
		)
	)
	(footprint ""
		(layer "F.Cu")
		(at 30.41904 -68.504054 90)
		(property "Reference" "R661"
			(at 0 0 90)
			(layer "F.SilkS")
			(hide yes)
			(effects
				(font
					(size 1.27 1.27)
				)
			)
		)
		(property "Value" ""
			(at 0 0 90)
			(layer "F.Fab")
			(effects
				(font
					(size 1.27 1.27)
				)
			)
		)
		(duplicate_pad_numbers_are_jumpers no)
		(fp_line
			(start 0.7874 -0.4064)
			(end 0.7874 0.4064)
			(stroke
				(width 0.1524)
				(type default)
			)
			(layer "F.SilkS")
		)
		(fp_line
			(start -0.7874 -0.4064)
			(end 0.7874 -0.4064)
			(stroke
				(width 0.1524)
				(type default)
			)
			(layer "F.SilkS")
		)
		(fp_line
			(start 0.7874 0.4064)
			(end -0.7874 0.4064)
			(stroke
				(width 0.1524)
				(type default)
			)
			(layer "F.SilkS")
		)
		(fp_line
			(start -0.7874 0.4064)
			(end -0.7874 -0.4064)
			(stroke
				(width 0.1524)
				(type default)
			)
			(layer "F.SilkS")
		)
		(fp_line
			(start -0.12065 -0.305054)
			(end -0.12065 -0.2794)
			(stroke
				(width 0.1)
				(type default)
			)
			(layer "F.Fab")
		)
		(fp_line
			(start -0.67945 -0.305054)
			(end -0.12065 -0.305054)
			(stroke
				(width 0.1)
				(type default)
			)
			(layer "F.Fab")
		)
		(fp_line
			(start 0.67945 -0.3048)
			(end 0.67945 0.3048)
			(stroke
				(width 0.1)
				(type default)
			)
			(layer "F.Fab")
		)
		(fp_line
			(start 0.12065 -0.3048)
			(end 0.67945 -0.3048)
			(stroke
				(width 0.1)
				(type default)
			)
			(layer "F.Fab")
		)
		(fp_line
			(start 0.12065 -0.2794)
			(end 0.12065 -0.3048)
			(stroke
				(width 0.1)
				(type default)
			)
			(layer "F.Fab")
		)
		(fp_line
			(start -0.12065 -0.2794)
			(end 0.12065 -0.2794)
			(stroke
				(width 0.1)
				(type default)
			)
			(layer "F.Fab")
		)
		(fp_line
			(start 0.120396 0.2794)
			(end -0.12065 0.2794)
			(stroke
				(width 0.1)
				(type default)
			)
			(layer "F.Fab")
		)
		(fp_line
			(start -0.12065 0.2794)
			(end -0.12065 0.3048)
			(stroke
				(width 0.1)
				(type default)
			)
			(layer "F.Fab")
		)
		(fp_line
			(start 0.67945 0.3048)
			(end 0.120396 0.3048)
			(stroke
				(width 0.1)
				(type default)
			)
			(layer "F.Fab")
		)
		(fp_line
			(start 0.120396 0.3048)
			(end 0.120396 0.2794)
			(stroke
				(width 0.1)
				(type default)
			)
			(layer "F.Fab")
		)
		(fp_line
			(start -0.12065 0.3048)
			(end -0.67945 0.3048)
			(stroke
				(width 0.1)
				(type default)
			)
			(layer "F.Fab")
		)
		(fp_line
			(start -0.67945 0.3048)
			(end -0.67945 -0.305054)
			(stroke
				(width 0.1)
				(type default)
			)
			(layer "F.Fab")
		)
		(pad "1" smd circle
			(at -0.40005 0 90)
			(size 0 0)
			(layers "F.Cu" "F.Mask" "F.Paste")
			(net "P3V3_AUX")
		)
		(pad "2" smd circle
			(at 0.40005 0 90)
			(size 0 0)
			(layers "F.Cu" "F.Mask" "F.Paste")
			(net "EMMC_DT6_R")
		)
	)
)
